# BASEBOARD_FAB2 (Tioga Pass) — schematic netlist excerpt (pin names and nets, part order shuffled) for the footprints in the layout excerpt that follows; sources: Cadence DE-HDL packaged netlist, KiCad conversion of Wiwynn_Tioga_Pass_MB.brd

U8D5  TTL1G126_A  74HC1G126 IC  pkg SOT  page 170
  OE  = FM_PMBUS_ALERT_BUF_EN
  A  = IRQ_SML1_PMBUS_ALERT_N
  Y  = IRQ_SML1_PMBUS_ALERT_BUF_N

C5D2  CAP_A  22.0UF 4V 20% X6S  pkg 0603V  page 220 : A = PVDDQ_DEF ; B = GND
C7A44  CAP  0.220UF 16V 10% X7R  pkg 0402  page 236 : A = VR_P1V05_PCH_STBY_PH1_BOOT ; B = VR_P1V05_PCH_STBY_PH1_PHASE

(kicad_pcb
	(version 20260206)
	(generator "pcbnew")
	(generator_version "10.0")
	(general
		(thickness 1.6)
		(legacy_teardrops no)
	)
	(paper "A4")
	(title_block
		(title "Wiwynn_Tioga_Pass_MB.brd")
		(comment 1 "Tioga Pass / footprints 1454-1456 of 4770")
	)
	(layers
		(0 "F.Cu" signal "TOP")
		(4 "In1.Cu" signal "L2GND")
		(6 "In2.Cu" signal "L3")
		(8 "In3.Cu" signal "L4GND")
		(10 "In4.Cu" signal "L5")
		(12 "In5.Cu" signal "L6GND")
		(14 "In6.Cu" signal "L7VCC")
		(16 "In7.Cu" signal "L8VCC")
		(18 "In8.Cu" signal "L9GND")
		(20 "In9.Cu" signal "L10")
		(22 "In10.Cu" signal "L11GND")
		(24 "In11.Cu" signal "L12")
		(26 "In12.Cu" signal "L13GND")
		(2 "B.Cu" signal "BOTTOM")
		(9 "F.Adhes" user "F.Adhesive")
		(11 "B.Adhes" user "B.Adhesive")
		(13 "F.Paste" user "Package Geometry/Pastemask Top")
		(15 "B.Paste" user "Package Geometry/Pastemask Bottom")
		(5 "F.SilkS" user "Ref Des/Silkscreen Top")
		(7 "B.SilkS" user "Ref Des/Silkscreen Bottom")
		(1 "F.Mask" user "Board Geometry/Soldermask Top")
		(3 "B.Mask" user "Board Geometry/Soldermask Bottom")
		(17 "Dwgs.User" user "User.Drawings")
		(19 "Cmts.User" user "User.Comments")
		(21 "Eco1.User" user "User.Eco1")
		(23 "Eco2.User" user "User.Eco2")
		(25 "Edge.Cuts" user "Board Geometry/Outline")
		(27 "Margin" user)
		(31 "F.CrtYd" user "Package Geometry/Place Bound Top")
		(29 "B.CrtYd" user "Package Geometry/Place Bound Bottom")
		(35 "F.Fab" user "Ref Des/Assembly Top")
		(33 "B.Fab" user "Ref Des/Assembly Bottom")
	)
	(footprint ""
		(layer "F.Cu")
		(at 389.60679 -157.493462 -90)
		(property "Reference" "C7A44"
			(at 0 0 270)
			(layer "F.SilkS")
			(hide yes)
			(effects
				(font
					(size 1.27 1.27)
				)
			)
		)
		(property "Value" ""
			(at 0 0 270)
			(layer "F.Fab")
			(effects
				(font
					(size 1.27 1.27)
				)
			)
		)
		(duplicate_pad_numbers_are_jumpers no)
		(fp_poly
			(pts
				(xy 0.3048 -0.1016) (xy 0.3048 0.9906) (xy -0.3048 0.9906) (xy -0.3048 -0.1016)
			)
			(stroke
				(width 0)
				(type default)
			)
			(fill no)
			(layer "F.CrtYd")
		)
		(fp_line
			(start -0.3048 0.9906)
			(end 0.3048 0.9906)
			(stroke
				(width 0.1)
				(type default)
			)
			(layer "F.Fab")
		)
		(fp_line
			(start 0.3048 0.9906)
			(end 0.3048 -0.1016)
			(stroke
				(width 0.1)
				(type default)
			)
			(layer "F.Fab")
		)
		(fp_line
			(start -0.3048 -0.1016)
			(end -0.3048 0.9906)
			(stroke
				(width 0.1)
				(type default)
			)
			(layer "F.Fab")
		)
		(fp_line
			(start 0.3048 -0.1016)
			(end -0.3048 -0.1016)
			(stroke
				(width 0.1)
				(type default)
			)
			(layer "F.Fab")
		)
		(pad "1" smd rect
			(at 0 0 270)
			(size 0.508 0.508)
			(layers "F.Cu" "F.Mask" "F.Paste")
			(net "VR_P1V05_PCH_STBY_PH1_BOOT")
		)
		(pad "2" smd rect
			(at 0 0.889 270)
			(size 0.508 0.508)
			(layers "F.Cu" "F.Mask" "F.Paste")
			(net "VR_P1V05_PCH_STBY_PH1_PHASE")
		)
		(zone
			(layer "F.Cu")
			(hatch none 0.5)
			(connect_pads
				(clearance 0)
			)
			(min_thickness 0.25)
			(keepout
				(tracks not_allowed)
				(vias allowed)
				(pads allowed)
				(copperpour not_allowed)
				(footprints allowed)
			)
			(placement
				(enabled no)
				(sheetname "")
			)
			(fill
				(thermal_gap 0.5)
				(thermal_bridge_width 0.5)
				(island_removal_mode 0)
			)
			(polygon
				(pts
					(xy 388.97179 -157.747462) (xy 388.97179 -157.239462) (xy 389.35279 -157.239462) (xy 389.35279 -157.747462)
				)
			)
		)
		(zone
			(layer "F.Cu")
			(hatch none 0.5)
			(connect_pads
				(clearance 0)
			)
			(min_thickness 0.25)
			(keepout
				(tracks allowed)
				(vias not_allowed)
				(pads allowed)
				(copperpour not_allowed)
				(footprints allowed)
			)
			(placement
				(enabled no)
				(sheetname "")
			)
			(fill
				(thermal_gap 0.5)
				(thermal_bridge_width 0.5)
				(island_removal_mode 0)
			)
			(polygon
				(pts
					(xy 389.35279 -157.747462) (xy 389.35279 -157.239462) (xy 388.97179 -157.239462) (xy 388.97179 -157.747462)
				)
			)
		)
	)
	(footprint ""
		(layer "F.Cu")
		(at 418.973 -83.580986)
		(property "Reference" "U8D5"
			(at 3.27025 2.02692 90)
			(unlocked yes)
			(layer "F.SilkS")
			(effects
				(font
					(size 0.7874 0.5842)
					(thickness 0.1524)
				)
				(justify left)
			)
		)
		(property "Value" ""
			(at 0 0 0)
			(layer "F.Fab")
			(effects
				(font
					(size 1.27 1.27)
				)
			)
		)
		(duplicate_pad_numbers_are_jumpers no)
		(fp_circle
			(center -0.4699 -0.8382)
			(end -0.3429 -0.8382)
			(stroke
				(width 0.254)
				(type default)
			)
			(fill no)
			(layer "F.SilkS")
		)
		(fp_poly
			(pts
				(xy 0.21463 -0.450088) (xy 1.56337 -0.450088) (xy 1.56337 1.75006) (xy 0.21463 1.75006)
			)
			(stroke
				(width 0)
				(type default)
			)
			(fill no)
			(layer "F.CrtYd")
		)
		(fp_line
			(start 0.21463 -0.450088)
			(end 1.56337 -0.450088)
			(stroke
				(width 0.1)
				(type default)
			)
			(layer "F.Fab")
		)
		(fp_line
			(start 0.21463 1.75006)
			(end 0.21463 -0.450088)
			(stroke
				(width 0.1)
				(type default)
			)
			(layer "F.Fab")
		)
		(fp_line
			(start 1.56337 -0.450088)
			(end 1.56337 1.75006)
			(stroke
				(width 0.1)
				(type default)
			)
			(layer "F.Fab")
		)
		(fp_line
			(start 1.56337 1.75006)
			(end 0.21463 1.75006)
			(stroke
				(width 0.1)
				(type default)
			)
			(layer "F.Fab")
		)
		(fp_circle
			(center -0.4699 -0.8382)
			(end -0.3429 -0.8382)
			(stroke
				(width 0.254)
				(type default)
			)
			(fill no)
			(layer "F.Fab")
		)
		(pad "1" smd rect
			(at 0 0)
			(size 1.016 0.381)
			(layers "F.Cu" "F.Mask" "F.Paste")
			(net "FM_PMBUS_ALERT_BUF_EN")
		)
		(pad "2" smd rect
			(at 0 0.649986)
			(size 1.016 0.381)
			(layers "F.Cu" "F.Mask" "F.Paste")
			(net "IRQ_SML1_PMBUS_ALERT_N")
		)
		(pad "3" smd rect
			(at 0 1.299972)
			(size 1.016 0.381)
			(layers "F.Cu" "F.Mask" "F.Paste")
			(net "GND")
		)
		(pad "4" smd rect
			(at 1.778 1.299972)
			(size 1.016 0.381)
			(layers "F.Cu" "F.Mask" "F.Paste")
			(net "IRQ_SML1_PMBUS_ALERT_BUF_N")
		)
		(pad "5" smd rect
			(at 1.778 0)
			(size 1.016 0.381)
			(layers "F.Cu" "F.Mask" "F.Paste")
			(net "P3V3_STBY")
		)
	)
	(footprint ""
		(layer "F.Cu")
		(at 269.75181 -84.890102)
		(property "Reference" "C5D2"
			(at 0 0 0)
			(layer "F.SilkS")
			(hide yes)
			(effects
				(font
					(size 1.27 1.27)
				)
			)
		)
		(property "Value" ""
			(at 0 0 0)
			(layer "F.Fab")
			(effects
				(font
					(size 1.27 1.27)
				)
			)
		)
		(duplicate_pad_numbers_are_jumpers no)
		(fp_poly
			(pts
				(xy -0.4953 -0.2032) (xy 0.4953 -0.2032) (xy 0.4953 1.6002) (xy -0.4953 1.6002)
			)
			(stroke
				(width 0)
				(type default)
			)
			(fill no)
			(layer "F.CrtYd")
		)
		(fp_line
			(start -0.4953 -0.2032)
			(end 0.4953 -0.2032)
			(stroke
				(width 0.1)
				(type default)
			)
			(layer "F.Fab")
		)
		(fp_line
			(start -0.4953 1.6002)
			(end -0.4953 -0.2032)
			(stroke
				(width 0.1)
				(type default)
			)
			(layer "F.Fab")
		)
		(fp_line
			(start 0.4953 -0.2032)
			(end 0.4953 1.6002)
			(stroke
				(width 0.1)
				(type default)
			)
			(layer "F.Fab")
		)
		(fp_line
			(start 0.4953 1.6002)
			(end -0.4953 1.6002)
			(stroke
				(width 0.1)
				(type default)
			)
			(layer "F.Fab")
		)
		(pad "1" smd rect
			(at 0 0)
			(size 0.762 0.889)
			(layers "F.Cu" "F.Mask" "F.Paste")
			(net "PVDDQ_DEF")
		)
		(pad "2" smd rect
			(at 0 1.397)
			(size 0.762 0.889)
			(layers "F.Cu" "F.Mask" "F.Paste")
			(net "GND")
		)
		(zone
			(layer "F.Cu")
			(hatch none 0.5)
			(connect_pads
				(clearance 0)
			)
			(min_thickness 0.25)
			(keepout
				(tracks not_allowed)
				(vias allowed)
				(pads allowed)
				(copperpour not_allowed)
				(footprints allowed)
			)
			(placement
				(enabled no)
				(sheetname "")
			)
			(fill
				(thermal_gap 0.5)
				(thermal_bridge_width 0.5)
				(island_removal_mode 0)
			)
			(polygon
				(pts
					(xy 269.37081 -84.445602) (xy 270.13281 -84.445602) (xy 270.13281 -83.937602) (xy 269.37081 -83.937602)
				)
			)
		)
	)
)
